(kicad_pcb
	(version 20260206)
	(generator "pcbnew")
	(generator_version "10.0")
	(general
		(thickness 1.6)
		(legacy_teardrops no)
	)
	(paper "A4")
	(title_block
		(title "Bryce Canyon_R.DPB_16317-1_OCP.brd")
		(comment 1 "Bryce Canyon / footprints 961-968 of 2099")
	)
	(layers
		(0 "F.Cu" signal "TOP")
		(4 "In1.Cu" signal "L2GND")
		(6 "In2.Cu" signal "L3")
		(8 "In3.Cu" signal "L4VCC")
		(10 "In4.Cu" signal "L5VCC")
		(12 "In5.Cu" signal "L6")
		(14 "In6.Cu" signal "L7GND")
		(2 "B.Cu" signal "BOTTOM")
		(9 "F.Adhes" user "F.Adhesive")
		(11 "B.Adhes" user "B.Adhesive")
		(13 "F.Paste" user "Package Geometry/Pastemask Top")
		(15 "B.Paste" user "Package Geometry/Pastemask Bottom")
		(5 "F.SilkS" user "Ref Des/Silkscreen Top")
		(7 "B.SilkS" user "Ref Des/Silkscreen Bottom")
		(1 "F.Mask" user "Board Geometry/Soldermask Top")
		(3 "B.Mask" user "Board Geometry/Soldermask Bottom")
		(17 "Dwgs.User" user "User.Drawings")
		(19 "Cmts.User" user "User.Comments")
		(21 "Eco1.User" user "User.Eco1")
		(23 "Eco2.User" user "User.Eco2")
		(25 "Edge.Cuts" user "Board Geometry/Outline")
		(27 "Margin" user)
		(31 "F.CrtYd" user "Package Geometry/Place Bound Top")
		(29 "B.CrtYd" user "Package Geometry/Place Bound Bottom")
		(35 "F.Fab" user "Ref Des/Assembly Top")
		(33 "B.Fab" user "Ref Des/Assembly Bottom")
	)
	(footprint ""
		(layer "F.Cu")
		(at 457.581 -32.004 -90)
		(property "Reference" "R851"
			(at 0 0 270)
			(layer "F.SilkS")
			(hide yes)
			(effects
				(font
					(size 1.27 1.27)
				)
			)
		)
		(property "Value" "2R6F-GP"
			(at -0.0508 -4.8514 270)
			(unlocked yes)
			(layer "F.Fab")
			(hide yes)
			(effects
				(font
					(size 1.016 1.016)
					(thickness 0.1524)
				)
			)
		)
		(property "Device Type" "R1206H26"
			(at 0 -6.3754 270)
			(unlocked yes)
			(layer "F.Fab")
			(hide yes)
			(effects
				(font
					(size 1.016 1.016)
					(thickness 0.1524)
				)
			)
		)
		(duplicate_pad_numbers_are_jumpers no)
		(fp_line
			(start -1.016 2.2352)
			(end -1.016 -2.2352)
			(stroke
				(width 0.1524)
				(type default)
			)
			(layer "F.SilkS")
		)
		(fp_line
			(start 1.016 2.2352)
			(end -1.016 2.2352)
			(stroke
				(width 0.1524)
				(type default)
			)
			(layer "F.SilkS")
		)
		(fp_line
			(start -1.016 -2.2352)
			(end 1.016 -2.2352)
			(stroke
				(width 0.1524)
				(type default)
			)
			(layer "F.SilkS")
		)
		(fp_line
			(start 1.016 -2.2352)
			(end 1.016 2.2352)
			(stroke
				(width 0.1524)
				(type default)
			)
			(layer "F.SilkS")
		)
		(fp_rect
			(start -1.0922 2.3114)
			(end 1.0922 -2.3114)
			(stroke
				(width 0)
				(type default)
			)
			(fill no)
			(layer "F.CrtYd")
		)
		(fp_poly
			(pts
				(xy -1.0922 -2.3114) (xy 1.0922 -2.3114) (xy 1.0922 2.3114) (xy -1.0922 2.3114)
			)
			(stroke
				(width 0)
				(type default)
			)
			(fill no)
			(layer "F.Fab")
		)
		(pad "1" smd rect
			(at 0 -1.397 270)
			(size 1.651 1.27)
			(layers "F.Cu" "F.Mask" "F.Paste")
			(net "P5V_HDD34")
		)
		(pad "2" smd rect
			(at 0 1.397 270)
			(size 1.651 1.27)
			(layers "F.Cu" "F.Mask" "F.Paste")
			(net "5V_PRE_34")
		)
	)
	(footprint ""
		(layer "F.Cu")
		(at 280.444448 -351.351342 90)
		(property "Reference" "R1129"
			(at 0 0 90)
			(layer "F.SilkS")
			(hide yes)
			(effects
				(font
					(size 1.27 1.27)
				)
			)
		)
		(property "Value" "0R2J-2-GP"
			(at 0.064008 -3.993896 90)
			(unlocked yes)
			(layer "F.Fab")
			(hide yes)
			(effects
				(font
					(size 1.016 1.016)
					(thickness 0.1524)
				)
			)
		)
		(property "Device Type" "R402H16"
			(at 0.064008 -5.517896 90)
			(unlocked yes)
			(layer "F.Fab")
			(hide yes)
			(effects
				(font
					(size 1.016 1.016)
					(thickness 0.1524)
				)
			)
		)
		(duplicate_pad_numbers_are_jumpers no)
		(fp_line
			(start 0.508 -0.9398)
			(end -0.508 -0.9398)
			(stroke
				(width 0.1524)
				(type default)
			)
			(layer "F.SilkS")
		)
		(fp_line
			(start -0.508 -0.9398)
			(end -0.508 0.9398)
			(stroke
				(width 0.1524)
				(type default)
			)
			(layer "F.SilkS")
		)
		(fp_rect
			(start -0.508 0.9398)
			(end 0.508 -0.9398)
			(stroke
				(width 0)
				(type default)
			)
			(fill no)
			(layer "F.CrtYd")
		)
		(fp_rect
			(start -0.508 0.9398)
			(end 0.508 -0.9398)
			(stroke
				(width 0)
				(type default)
			)
			(fill no)
			(layer "F.Fab")
		)
		(pad "1" smd custom
			(at 0 -0.4445 90)
			(size 0.1397 0.1397)
			(layers "F.Cu" "F.Mask" "F.Paste")
			(net "P3V3_STBY_B")
			(options
				(clearance outline)
				(anchor circle)
			)
			(primitives
				(gr_poly
					(pts
						(arc
							(start -0.1778 -0.2794)
							(mid -0.249642 -0.249642)
							(end -0.2794 -0.1778)
						)
						(arc
							(start -0.2794 0.1778)
							(mid -0.249642 0.249642)
							(end -0.1778 0.2794)
						)
						(arc
							(start 0.1778 0.2794)
							(mid 0.249642 0.249642)
							(end 0.2794 0.1778)
						)
						(arc
							(start 0.2794 -0.1778)
							(mid 0.249642 -0.249642)
							(end 0.1778 -0.2794)
						)
					)
					(width 0)
					(fill yes)
				)
			)
		)
		(pad "2" smd custom
			(at 0 0.4445 90)
			(size 0.1397 0.1397)
			(layers "F.Cu" "F.Mask" "F.Paste")
			(net "MAX31790_B_PWM_ST0")
			(options
				(clearance outline)
				(anchor circle)
			)
			(primitives
				(gr_poly
					(pts
						(arc
							(start -0.1778 -0.2794)
							(mid -0.249642 -0.249642)
							(end -0.2794 -0.1778)
						)
						(arc
							(start -0.2794 0.1778)
							(mid -0.249642 0.249642)
							(end -0.1778 0.2794)
						)
						(arc
							(start 0.1778 0.2794)
							(mid 0.249642 0.249642)
							(end 0.2794 0.1778)
						)
						(arc
							(start 0.2794 -0.1778)
							(mid 0.249642 -0.249642)
							(end 0.1778 -0.2794)
						)
					)
					(width 0)
					(fill yes)
				)
			)
		)
	)
	(footprint ""
		(layer "F.Cu")
		(at 143.002 -254.127 -90)
		(property "Reference" "C90"
			(at 0 0 270)
			(layer "F.SilkS")
			(hide yes)
			(effects
				(font
					(size 1.27 1.27)
				)
			)
		)
		(property "Value" "SCD033U25V2KX-GP"
			(at 1.1811 -2.7051 270)
			(unlocked yes)
			(layer "F.Fab")
			(hide yes)
			(effects
				(font
					(size 1.016 1.016)
					(thickness 0.1524)
				)
			)
		)
		(property "Device Type" "C402H22"
			(at 1.1811 -4.2291 270)
			(unlocked yes)
			(layer "F.Fab")
			(hide yes)
			(effects
				(font
					(size 1.016 1.016)
					(thickness 0.1524)
				)
			)
		)
		(duplicate_pad_numbers_are_jumpers no)
		(fp_rect
			(start -0.4318 0.9525)
			(end 0.4318 -0.9525)
			(stroke
				(width 0)
				(type default)
			)
			(fill no)
			(layer "F.CrtYd")
		)
		(fp_rect
			(start -0.4318 0.9525)
			(end 0.4318 -0.9525)
			(stroke
				(width 0)
				(type default)
			)
			(fill no)
			(layer "F.Fab")
		)
		(pad "1" smd custom
			(at 0 -0.4445 270)
			(size 0.1524 0.1524)
			(layers "F.Cu" "F.Mask" "F.Paste")
			(net "SW_HDD_P4")
			(options
				(clearance outline)
				(anchor circle)
			)
			(primitives
				(gr_poly
					(pts
						(arc
							(start 0.3048 -0.2032)
							(mid 0.275042 -0.275042)
							(end 0.2032 -0.3048)
						)
						(arc
							(start -0.2032 -0.3048)
							(mid -0.275042 -0.275042)
							(end -0.3048 -0.2032)
						)
						(arc
							(start -0.3048 0.2032)
							(mid -0.275042 0.275042)
							(end -0.2032 0.3048)
						)
						(arc
							(start 0.2032 0.3048)
							(mid 0.275042 0.275042)
							(end 0.3048 0.2032)
						)
					)
					(width 0)
					(fill yes)
				)
			)
		)
		(pad "2" smd custom
			(at 0 0.4445 270)
			(size 0.1524 0.1524)
			(layers "F.Cu" "F.Mask" "F.Paste")
			(net "GND")
			(options
				(clearance outline)
				(anchor circle)
			)
			(primitives
				(gr_poly
					(pts
						(arc
							(start 0.3048 -0.2032)
							(mid 0.275042 -0.275042)
							(end 0.2032 -0.3048)
						)
						(arc
							(start -0.2032 -0.3048)
							(mid -0.275042 -0.275042)
							(end -0.3048 -0.2032)
						)
						(arc
							(start -0.3048 0.2032)
							(mid -0.275042 0.275042)
							(end -0.2032 0.3048)
						)
						(arc
							(start 0.2032 0.3048)
							(mid 0.275042 0.275042)
							(end 0.3048 0.2032)
						)
					)
					(width 0)
					(fill yes)
				)
			)
		)
	)
	(footprint ""
		(layer "F.Cu")
		(at 55.118 -11.049 180)
		(property "Reference" "R659"
			(at 0 0 180)
			(layer "F.SilkS")
			(hide yes)
			(effects
				(font
					(size 1.27 1.27)
				)
			)
		)
		(property "Value" "4K7R2J-2-GP"
			(at 0.064008 -3.993896 180)
			(unlocked yes)
			(layer "F.Fab")
			(hide yes)
			(effects
				(font
					(size 1.016 1.016)
					(thickness 0.1524)
				)
			)
		)
		(property "Device Type" "R402H16"
			(at 0.064008 -5.517896 180)
			(unlocked yes)
			(layer "F.Fab")
			(hide yes)
			(effects
				(font
					(size 1.016 1.016)
					(thickness 0.1524)
				)
			)
		)
		(duplicate_pad_numbers_are_jumpers no)
		(fp_line
			(start 0.508 -0.9398)
			(end -0.508 -0.9398)
			(stroke
				(width 0.1524)
				(type default)
			)
			(layer "F.SilkS")
		)
		(fp_line
			(start -0.508 -0.9398)
			(end -0.508 0.9398)
			(stroke
				(width 0.1524)
				(type default)
			)
			(layer "F.SilkS")
		)
		(fp_rect
			(start -0.508 0.9398)
			(end 0.508 -0.9398)
			(stroke
				(width 0)
				(type default)
			)
			(fill no)
			(layer "F.CrtYd")
		)
		(fp_rect
			(start -0.508 0.9398)
			(end 0.508 -0.9398)
			(stroke
				(width 0)
				(type default)
			)
			(fill no)
			(layer "F.Fab")
		)
		(pad "1" smd custom
			(at 0 -0.4445 180)
			(size 0.1397 0.1397)
			(layers "F.Cu" "F.Mask" "F.Paste")
			(net "P12V_B")
			(options
				(clearance outline)
				(anchor circle)
			)
			(primitives
				(gr_poly
					(pts
						(arc
							(start -0.1778 -0.2794)
							(mid -0.249642 -0.249642)
							(end -0.2794 -0.1778)
						)
						(arc
							(start -0.2794 0.1778)
							(mid -0.249642 0.249642)
							(end -0.1778 0.2794)
						)
						(arc
							(start 0.1778 0.2794)
							(mid 0.249642 0.249642)
							(end 0.2794 0.1778)
						)
						(arc
							(start 0.2794 -0.1778)
							(mid 0.249642 -0.249642)
							(end 0.1778 -0.2794)
						)
					)
					(width 0)
					(fill yes)
				)
			)
		)
		(pad "2" smd custom
			(at 0 0.4445 180)
			(size 0.1397 0.1397)
			(layers "F.Cu" "F.Mask" "F.Paste")
			(net "SW_HDD_R25")
			(options
				(clearance outline)
				(anchor circle)
			)
			(primitives
				(gr_poly
					(pts
						(arc
							(start -0.1778 -0.2794)
							(mid -0.249642 -0.249642)
							(end -0.2794 -0.1778)
						)
						(arc
							(start -0.2794 0.1778)
							(mid -0.249642 0.249642)
							(end -0.1778 0.2794)
						)
						(arc
							(start 0.1778 0.2794)
							(mid 0.249642 0.249642)
							(end 0.2794 0.1778)
						)
						(arc
							(start 0.2794 -0.1778)
							(mid 0.249642 -0.249642)
							(end 0.1778 -0.2794)
						)
					)
					(width 0)
					(fill yes)
				)
			)
		)
	)
	(footprint ""
		(layer "F.Cu")
		(at 253.096522 -358.622346)
		(property "Reference" "R1046"
			(at 0 0 0)
			(layer "F.SilkS")
			(hide yes)
			(effects
				(font
					(size 1.27 1.27)
				)
			)
		)
		(property "Value" "12K4R2F-GP"
			(at 0.064008 -3.993896 0)
			(unlocked yes)
			(layer "F.Fab")
			(hide yes)
			(effects
				(font
					(size 1.016 1.016)
					(thickness 0.1524)
				)
			)
		)
		(property "Device Type" "R402H16"
			(at 0.064008 -5.517896 0)
			(unlocked yes)
			(layer "F.Fab")
			(hide yes)
			(effects
				(font
					(size 1.016 1.016)
					(thickness 0.1524)
				)
			)
		)
		(duplicate_pad_numbers_are_jumpers no)
		(fp_line
			(start -0.508 -0.9398)
			(end -0.508 0.9398)
			(stroke
				(width 0.1524)
				(type default)
			)
			(layer "F.SilkS")
		)
		(fp_line
			(start 0.508 -0.9398)
			(end -0.508 -0.9398)
			(stroke
				(width 0.1524)
				(type default)
			)
			(layer "F.SilkS")
		)
		(fp_rect
			(start -0.508 0.9398)
			(end 0.508 -0.9398)
			(stroke
				(width 0)
				(type default)
			)
			(fill no)
			(layer "F.CrtYd")
		)
		(fp_rect
			(start -0.508 0.9398)
			(end 0.508 -0.9398)
			(stroke
				(width 0)
				(type default)
			)
			(fill no)
			(layer "F.Fab")
		)
		(pad "1" smd custom
			(at 0 -0.4445)
			(size 0.1397 0.1397)
			(layers "F.Cu" "F.Mask" "F.Paste")
			(net "MB3_ISTART_R")
			(options
				(clearance outline)
				(anchor circle)
			)
			(primitives
				(gr_poly
					(pts
						(arc
							(start -0.1778 -0.2794)
							(mid -0.249642 -0.249642)
							(end -0.2794 -0.1778)
						)
						(arc
							(start -0.2794 0.1778)
							(mid -0.249642 0.249642)
							(end -0.1778 0.2794)
						)
						(arc
							(start 0.1778 0.2794)
							(mid 0.249642 0.249642)
							(end 0.2794 0.1778)
						)
						(arc
							(start 0.2794 -0.1778)
							(mid 0.249642 -0.249642)
							(end 0.1778 -0.2794)
						)
					)
					(width 0)
					(fill yes)
				)
			)
		)
		(pad "2" smd custom
			(at 0 0.4445)
			(size 0.1397 0.1397)
			(layers "F.Cu" "F.Mask" "F.Paste")
			(net "AGND_CURRENT_DPB")
			(options
				(clearance outline)
				(anchor circle)
			)
			(primitives
				(gr_poly
					(pts
						(arc
							(start -0.1778 -0.2794)
							(mid -0.249642 -0.249642)
							(end -0.2794 -0.1778)
						)
						(arc
							(start -0.2794 0.1778)
							(mid -0.249642 0.249642)
							(end -0.1778 0.2794)
						)
						(arc
							(start 0.1778 0.2794)
							(mid 0.249642 0.249642)
							(end 0.2794 0.1778)
						)
						(arc
							(start 0.2794 -0.1778)
							(mid 0.249642 -0.249642)
							(end 0.1778 -0.2794)
						)
					)
					(width 0)
					(fill yes)
				)
			)
		)
	)
	(footprint ""
		(layer "F.Cu")
		(at 232.13949 -353.280726 180)
		(property "Reference" "C518"
			(at 0 0 180)
			(layer "F.SilkS")
			(hide yes)
			(effects
				(font
					(size 1.27 1.27)
				)
			)
		)
		(property "Value" "SC22U25V6KX-2-GP-U"
			(at -2.860802 -5.279644 180)
			(unlocked yes)
			(layer "F.Fab")
			(hide yes)
			(effects
				(font
					(size 1.016 1.016)
					(thickness 0.1524)
				)
			)
		)
		(property "Device Type" "C1206-TO0D3H75"
			(at -2.860802 -6.803644 180)
			(unlocked yes)
			(layer "F.Fab")
			(hide yes)
			(effects
				(font
					(size 1.016 1.016)
					(thickness 0.1524)
				)
			)
		)
		(duplicate_pad_numbers_are_jumpers no)
		(fp_line
			(start 1.3081 2.3749)
			(end -1.3081 2.3749)
			(stroke
				(width 0.1524)
				(type default)
			)
			(layer "F.SilkS")
		)
		(fp_line
			(start 1.3081 -2.3749)
			(end 1.3081 2.3749)
			(stroke
				(width 0.1524)
				(type default)
			)
			(layer "F.SilkS")
		)
		(fp_line
			(start -1.3081 2.3749)
			(end -1.3081 -2.3749)
			(stroke
				(width 0.1524)
				(type default)
			)
			(layer "F.SilkS")
		)
		(fp_line
			(start -1.3081 -2.3749)
			(end 1.3081 -2.3749)
			(stroke
				(width 0.1524)
				(type default)
			)
			(layer "F.SilkS")
		)
		(fp_rect
			(start -0.8001 1.6002)
			(end 0.8001 -1.6002)
			(stroke
				(width 0)
				(type default)
			)
			(fill no)
			(layer "F.CrtYd")
		)
		(fp_poly
			(pts
				(xy -1.5621 2.4511) (xy -1.5621 1.6002) (xy 0.8001 1.6002) (xy 0.8001 -1.6002) (xy -0.8001 -1.6002)
				(xy -0.8001 1.5875) (xy -1.5621 1.5875) (xy -1.5621 -2.4511) (xy 1.5621 -2.4511) (xy 1.5621 2.4511)
			)
			(stroke
				(width 0)
				(type default)
			)
			(fill no)
			(layer "F.CrtYd")
		)
		(fp_rect
			(start -1.5621 2.4511)
			(end 1.5621 -2.4511)
			(stroke
				(width 0)
				(type default)
			)
			(fill no)
			(layer "F.Fab")
		)
		(pad "1" smd rect
			(at 0 -1.392936 180)
			(size 2.1082 1.4478)
			(layers "F.Cu" "F.Mask" "F.Paste")
			(net "P12V_IN")
		)
		(pad "2" smd rect
			(at 0 1.392936 180)
			(size 2.1082 1.4478)
			(layers "F.Cu" "F.Mask" "F.Paste")
			(net "GND")
		)
	)
	(footprint ""
		(layer "F.Cu")
		(at 319.216024 -154.70505)
		(property "Reference" "TP111"
			(at 0 0 0)
			(layer "F.SilkS")
			(hide yes)
			(effects
				(font
					(size 1.27 1.27)
				)
			)
		)
		(property "Value" "*"
			(at -0.0508 -1.6764 0)
			(unlocked yes)
			(layer "F.Fab")
			(hide yes)
			(effects
				(font
					(size 1.016 1.016)
					(thickness 0.1524)
				)
			)
		)
		(property "Device Type" "TPAD32"
			(at -0.0508 -3.2004 0)
			(unlocked yes)
			(layer "F.Fab")
			(hide yes)
			(effects
				(font
					(size 1.016 1.016)
					(thickness 0.1524)
				)
			)
		)
		(duplicate_pad_numbers_are_jumpers no)
		(fp_poly
			(pts
				(arc
					(start 0.4064 0)
					(mid -0.4064 0)
					(end 0.4064 0)
				)
			)
			(stroke
				(width 0)
				(type default)
			)
			(fill no)
			(layer "F.CrtYd")
		)
		(fp_poly
			(pts
				(arc
					(start 0.7112 0)
					(mid -0.7112 0)
					(end 0.7112 0)
				)
			)
			(stroke
				(width 0)
				(type default)
			)
			(fill no)
			(layer "F.Fab")
		)
		(pad "1" smd circle
			(at 0 0)
			(size 0.8128 0.8128)
			(layers "F.Cu" "F.Mask" "F.Paste")
			(net "ACT_HDD_18")
		)
	)
	(footprint ""
		(layer "F.Cu")
		(at 462.788 -33.02)
		(property "Reference" "Q180"
			(at 0 0 0)
			(layer "F.SilkS")
			(hide yes)
			(effects
				(font
					(size 1.27 1.27)
				)
			)
		)
		(property "Value" "AO4407AL-GP"
			(at -3.707384 -1.5367 0)
			(unlocked yes)
			(layer "F.Fab")
			(hide yes)
			(effects
				(font
					(size 1.016 1.016)
					(thickness 0.1524)
				)
			)
		)
		(property "Device Type" "SOIC8H69"
			(at -3.707384 -3.0607 0)
			(unlocked yes)
			(layer "F.Fab")
			(hide yes)
			(effects
				(font
					(size 1.016 1.016)
					(thickness 0.1524)
				)
			)
		)
		(duplicate_pad_numbers_are_jumpers no)
		(fp_line
			(start -2.7432 -1.4224)
			(end -2.7432 1.4224)
			(stroke
				(width 0.1524)
				(type default)
			)
			(layer "F.SilkS")
		)
		(fp_line
			(start -2.7432 1.4224)
			(end -2.6416 1.4224)
			(stroke
				(width 0.1524)
				(type default)
			)
			(layer "F.SilkS")
		)
		(fp_line
			(start -2.7432 1.4224)
			(end 2.1336 1.4224)
			(stroke
				(width 0.1524)
				(type default)
			)
			(layer "F.SilkS")
		)
		(fp_line
			(start -2.7178 -0.508)
			(end -2.1844 -0.0508)
			(stroke
				(width 0.1524)
				(type default)
			)
			(layer "F.SilkS")
		)
		(fp_line
			(start -2.6289 3.4417)
			(end -2.6289 1.4732)
			(stroke
				(width 0.381)
				(type default)
			)
			(layer "F.SilkS")
		)
		(fp_line
			(start -2.1844 -0.0508)
			(end -2.7178 0.508)
			(stroke
				(width 0.1524)
				(type default)
			)
			(layer "F.SilkS")
		)
		(fp_line
			(start 2.1336 -1.4224)
			(end -2.7432 -1.4224)
			(stroke
				(width 0.1524)
				(type default)
			)
			(layer "F.SilkS")
		)
		(fp_line
			(start 2.1336 1.4224)
			(end 2.1336 -1.4224)
			(stroke
				(width 0.1524)
				(type default)
			)
			(layer "F.SilkS")
		)
		(fp_poly
			(pts
				(xy -2.2098 -1.4224) (xy -2.2098 1.4224) (xy 2.2098 1.4224) (xy 2.2098 -1.4224)
			)
			(stroke
				(width 0)
				(type default)
			)
			(fill yes)
			(layer "F.SilkS")
		)
		(fp_rect
			(start -2.450084 2.999994)
			(end 2.450084 -2.999994)
			(stroke
				(width 0)
				(type default)
			)
			(fill no)
			(layer "F.CrtYd")
		)
		(fp_poly
			(pts
				(xy -2.8194 3.6322) (xy -2.8194 -3.6322) (xy 2.8194 -3.6322) (xy 2.8194 1.18364) (xy 2.450084 1.18364)
				(xy 2.450084 -2.999994) (xy -2.450084 -2.999994) (xy -2.450084 2.999994) (xy 2.450084 2.999994)
				(xy 2.450084 1.18618) (xy 2.8194 1.18618) (xy 2.8194 3.6322)
			)
			(stroke
				(width 0)
				(type default)
			)
			(fill no)
			(layer "F.CrtYd")
		)
		(fp_rect
			(start -2.8194 3.6322)
			(end 2.8194 -3.6322)
			(stroke
				(width 0)
				(type default)
			)
			(fill no)
			(layer "F.Fab")
		)
		(pad "1" smd rect
			(at -1.905 2.54)
			(size 0.635 1.651)
			(layers "F.Cu" "F.Mask" "F.Paste")
			(net "P12V_B")
		)
		(pad "2" smd rect
			(at -0.635 2.54)
			(size 0.635 1.651)
			(layers "F.Cu" "F.Mask" "F.Paste")
			(net "P12V_B")
		)
		(pad "3" smd rect
			(at 0.635 2.54)
			(size 0.635 1.651)
			(layers "F.Cu" "F.Mask" "F.Paste")
			(net "P12V_B")
		)
		(pad "4" smd rect
			(at 1.905 2.54)
			(size 0.635 1.651)
			(layers "F.Cu" "F.Mask" "F.Paste")
			(net "SW_HDD_N34")
		)
		(pad "5" smd rect
			(at 1.905 -2.54)
			(size 0.635 1.651)
			(layers "F.Cu" "F.Mask" "F.Paste")
			(net "P12V_HDD34")
		)
		(pad "6" smd rect
			(at 0.635 -2.54)
			(size 0.635 1.651)
			(layers "F.Cu" "F.Mask" "F.Paste")
			(net "P12V_HDD34")
		)
		(pad "7" smd rect
			(at -0.635 -2.54)
			(size 0.635 1.651)
			(layers "F.Cu" "F.Mask" "F.Paste")
			(net "P12V_HDD34")
		)
		(pad "8" smd rect
			(at -1.905 -2.54)
			(size 0.635 1.651)
			(layers "F.Cu" "F.Mask" "F.Paste")
			(net "P12V_HDD34")
		)
	)
)
